(kicad_pcb
	(version 20240108)
	(generator "pcbnew")
	(generator_version "8.0")
	(general
		(thickness 1.62)
		(legacy_teardrops no)
	)
	(paper "A4")
	(title_block
		(title "Jetson Orin Baseboard")
		(date "2025-03-12")
		(rev "1.3.4")
		(company "Antmicro Ltd")
		(comment 1 "www.antmicro.com")
		(comment 9 "footprints 398-401 of 677")
	)
	(layers
		(0 "F.Cu" signal)
		(1 "In1.Cu" signal)
		(2 "In2.Cu" signal)
		(3 "In3.Cu" signal)
		(4 "In4.Cu" jumper)
		(5 "In5.Cu" signal)
		(6 "In6.Cu" signal)
		(31 "B.Cu" signal)
		(32 "B.Adhes" user "B.Adhesive")
		(33 "F.Adhes" user "F.Adhesive")
		(34 "B.Paste" user)
		(35 "F.Paste" user)
		(36 "B.SilkS" user "B.Silkscreen")
		(37 "F.SilkS" user "F.Silkscreen")
		(38 "B.Mask" user)
		(39 "F.Mask" user)
		(40 "Dwgs.User" user "User.Drawings")
		(41 "Cmts.User" user "User.Comments")
		(42 "Eco1.User" user "User.Eco1")
		(43 "Eco2.User" user "User.Eco2")
		(44 "Edge.Cuts" user)
		(45 "Margin" user)
		(46 "B.CrtYd" user "B.Courtyard")
		(47 "F.CrtYd" user "F.Courtyard")
		(48 "B.Fab" user)
		(49 "F.Fab" user)
	)
	(footprint "antmicro-footprints:R_0402_1005Metric"
		(layer "B.Cu")
		(at 74.12 77.03 -90)
		(descr "Resistor SMD 0402")
		(tags "resistor SMD 0402")
		(property "Reference" "R183"
			(at -1.155 -1.45 90)
			(layer "B.SilkS")
			(effects
				(font
					(size 0.7 0.7)
					(thickness 0.15)
				)
				(justify left bottom mirror)
			)
		)
		(property "Value" "R_0R_0402"
			(at 0 -1.4 90)
			(layer "B.Fab")
			(effects
				(font
					(size 0.7 0.7)
					(thickness 0.15)
				)
				(justify left bottom mirror)
			)
		)
		(property "Footprint" "antmicro-footprints:R_0402_1005Metric"
			(at 0 0 -90)
			(layer "F.Fab")
			(hide yes)
			(effects
				(font
					(size 1.27 1.27)
					(thickness 0.15)
				)
			)
		)
		(property "Datasheet" "https://industrial.panasonic.com/cdbs/www-data/pdf/RDA0000/AOA0000C301.pdf"
			(at 0 0 -90)
			(layer "F.Fab")
			(hide yes)
			(effects
				(font
					(size 1.27 1.27)
					(thickness 0.15)
				)
			)
		)
		(property "Author" "Antmicro"
			(at -2.91 151.15 0)
			(layer "B.Fab")
			(hide yes)
			(effects
				(font
					(size 1 1)
					(thickness 0.15)
				)
				(justify mirror)
			)
		)
		(property "Current" "1A"
			(at -2.91 151.15 0)
			(layer "B.Fab")
			(hide yes)
			(effects
				(font
					(size 1 1)
					(thickness 0.15)
				)
				(justify mirror)
			)
		)
		(property "License" "Apache-2.0"
			(at -2.91 151.15 0)
			(layer "B.Fab")
			(hide yes)
			(effects
				(font
					(size 1 1)
					(thickness 0.15)
				)
				(justify mirror)
			)
		)
		(property "MPN" "ERJ2GE0R00X"
			(at -2.91 151.15 0)
			(layer "B.Fab")
			(hide yes)
			(effects
				(font
					(size 1 1)
					(thickness 0.15)
				)
				(justify mirror)
			)
		)
		(property "Manufacturer" "Panasonic"
			(at -2.91 151.15 0)
			(layer "B.Fab")
			(hide yes)
			(effects
				(font
					(size 1 1)
					(thickness 0.15)
				)
				(justify mirror)
			)
		)
		(property "Tolerance" ""
			(at -2.91 151.15 0)
			(layer "B.Fab")
			(hide yes)
			(effects
				(font
					(size 1 1)
					(thickness 0.15)
				)
				(justify mirror)
			)
		)
		(property "Val" "0R"
			(at -2.91 151.15 0)
			(layer "B.Fab")
			(hide yes)
			(effects
				(font
					(size 1 1)
					(thickness 0.15)
				)
				(justify mirror)
			)
		)
		(sheetname "Supply")
		(sheetfile "supply.kicad_sch")
		(attr smd exclude_from_pos_files exclude_from_bom dnp)
		(fp_rect
			(start -0.925 0.47)
			(end 0.925 -0.47)
			(stroke
				(width 0.05)
				(type default)
			)
			(fill none)
			(layer "B.CrtYd")
		)
		(fp_rect
			(start -0.5 0.25)
			(end 0.5 -0.25)
			(stroke
				(width 0.15)
				(type solid)
			)
			(fill none)
			(layer "B.Fab")
		)
		(fp_text user "Author: Antmicro"
			(at -0.95 -4.169 90)
			(layer "B.Fab")
			(hide yes)
			(effects
				(font
					(size 0.7 0.7)
					(thickness 0.15)
				)
				(justify left bottom mirror)
			)
		)
		(fp_text user "License: Apache-2.0"
			(at -0.95 -5.169 90)
			(layer "B.Fab")
			(hide yes)
			(effects
				(font
					(size 0.7 0.7)
					(thickness 0.15)
				)
				(justify left bottom mirror)
			)
		)
		(fp_text user "${REFERENCE}"
			(at -0.95 -3.168 90)
			(layer "B.Fab")
			(hide yes)
			(effects
				(font
					(size 0.7 0.7)
					(thickness 0.15)
				)
				(justify left bottom mirror)
			)
		)
		(pad "1" smd roundrect
			(at -0.48 0 270)
			(size 0.59 0.64)
			(layers "B.Cu" "B.Paste" "B.Mask")
			(roundrect_rratio 0.25)
			(net 86 "~{RESET}")
			(pintype "passive")
		)
		(pad "2" smd roundrect
			(at 0.48 0 270)
			(size 0.59 0.64)
			(layers "B.Cu" "B.Paste" "B.Mask")
			(roundrect_rratio 0.25)
			(net 117 "3V3_STDB")
			(pintype "passive")
		)
	)
	(footprint "antmicro-footprints:LED_0603_1608Metric_G"
		(layer "B.Cu")
		(at 136.7 126 90)
		(descr "LED SMD 0603 Green")
		(tags "LED SMD 0603 Green")
		(property "Reference" "D54"
			(at -2.3 -1.15 180)
			(layer "B.SilkS")
			(effects
				(font
					(size 0.7 0.7)
					(thickness 0.15)
				)
				(justify right bottom mirror)
			)
		)
		(property "Value" "LED_G_0603_LTST-C190GKT"
			(at -0.001 -1.599 90)
			(layer "B.Fab")
			(effects
				(font
					(size 0.7 0.7)
					(thickness 0.15)
				)
				(justify right bottom mirror)
			)
		)
		(property "Footprint" "antmicro-footprints:LED_0603_1608Metric_G"
			(at 0 0 90)
			(layer "F.Fab")
			(hide yes)
			(effects
				(font
					(size 1.27 1.27)
					(thickness 0.15)
				)
			)
		)
		(property "Datasheet" "https://media.digikey.com/pdf/Data%20Sheets/Lite-On%20PDFs/LTST-C190GKT.pdf"
			(at 0 0 90)
			(layer "F.Fab")
			(hide yes)
			(effects
				(font
					(size 1.27 1.27)
					(thickness 0.15)
				)
			)
		)
		(property "Author" "Antmicro"
			(at 262.7 -10.7 0)
			(layer "B.Fab")
			(hide yes)
			(effects
				(font
					(size 1 1)
					(thickness 0.15)
				)
				(justify mirror)
			)
		)
		(property "Color" "Green"
			(at 262.7 -10.7 0)
			(layer "B.Fab")
			(hide yes)
			(effects
				(font
					(size 1 1)
					(thickness 0.15)
				)
				(justify mirror)
			)
		)
		(property "License" "Apache-2.0"
			(at 262.7 -10.7 0)
			(layer "B.Fab")
			(hide yes)
			(effects
				(font
					(size 1 1)
					(thickness 0.15)
				)
				(justify mirror)
			)
		)
		(property "MPN" "LTST-C190GKT"
			(at 262.7 -10.7 0)
			(layer "B.Fab")
			(hide yes)
			(effects
				(font
					(size 1 1)
					(thickness 0.15)
				)
				(justify mirror)
			)
		)
		(property "Manufacturer" "Lite-On"
			(at 262.7 -10.7 0)
			(layer "B.Fab")
			(hide yes)
			(effects
				(font
					(size 1 1)
					(thickness 0.15)
				)
				(justify mirror)
			)
		)
		(sheetname "Peripherals")
		(sheetfile "peripherals.kicad_sch")
		(attr smd)
		(fp_line
			(start -0.22 -0.35)
			(end 0.22 -0.35)
			(stroke
				(width 0.15)
				(type solid)
			)
			(layer "B.SilkS")
		)
		(fp_line
			(start -1.18 -0.321)
			(end -1.18 0.319)
			(stroke
				(width 0.15)
				(type solid)
			)
			(layer "B.SilkS")
		)
		(fp_line
			(start -0.094672 -0.001008)
			(end 0.105328 -0.201008)
			(stroke
				(width 0.1)
				(type solid)
			)
			(layer "B.SilkS")
		)
		(fp_line
			(start -0.24 -0.001008)
			(end -0.094672 -0.001008)
			(stroke
				(width 0.1)
				(type solid)
			)
			(layer "B.SilkS")
		)
		(fp_line
			(start 0.24 -0.001)
			(end 0.105328 -0.001008)
			(stroke
				(width 0.1)
				(type solid)
			)
			(layer "B.SilkS")
		)
		(fp_line
			(start 0.105328 0.198992)
			(end 0.105328 -0.201008)
			(stroke
				(width 0.1)
				(type solid)
			)
			(layer "B.SilkS")
		)
		(fp_line
			(start 0.105328 0.198992)
			(end -0.094672 -0.001008)
			(stroke
				(width 0.1)
				(type solid)
			)
			(layer "B.SilkS")
		)
		(fp_line
			(start -0.094672 0.198992)
			(end -0.094672 -0.201008)
			(stroke
				(width 0.1)
				(type solid)
			)
			(layer "B.SilkS")
		)
		(fp_line
			(start -0.22 0.35)
			(end 0.22 0.35)
			(stroke
				(width 0.15)
				(type solid)
			)
			(layer "B.SilkS")
		)
		(fp_rect
			(start 1.25 -0.65)
			(end -1.25 0.65)
			(stroke
				(width 0.05)
				(type solid)
			)
			(fill none)
			(layer "B.CrtYd")
		)
		(fp_line
			(start 0.201 -0.2)
			(end -0.101 0)
			(stroke
				(width 0.15)
				(type solid)
			)
			(layer "B.Fab")
		)
		(fp_line
			(start -0.199 -0.1)
			(end -0.199 -0.2)
			(stroke
				(width 0.15)
				(type solid)
			)
			(layer "B.Fab")
		)
		(fp_line
			(start -0.199 -0.1)
			(end -0.199 0.202)
			(stroke
				(width 0.15)
				(type solid)
			)
			(layer "B.Fab")
		)
		(fp_line
			(start 0.201 0)
			(end 0.201 -0.2)
			(stroke
				(width 0.15)
				(type solid)
			)
			(layer "B.Fab")
		)
		(fp_line
			(start 0.201 0)
			(end 0.599 0)
			(stroke
				(width 0.15)
				(type solid)
			)
			(layer "B.Fab")
		)
		(fp_line
			(start -0.101 0)
			(end 0.201 0.202)
			(stroke
				(width 0.15)
				(type solid)
			)
			(layer "B.Fab")
		)
		(fp_line
			(start -0.597 0)
			(end -0.199 0)
			(stroke
				(width 0.15)
				(type solid)
			)
			(layer "B.Fab")
		)
		(fp_line
			(start 0.201 0.202)
			(end 0.201 0)
			(stroke
				(width 0.15)
				(type solid)
			)
			(layer "B.Fab")
		)
		(fp_rect
			(start 0.848 -0.4)
			(end -0.85 0.402)
			(stroke
				(width 0.15)
				(type solid)
			)
			(fill none)
			(layer "B.Fab")
		)
		(fp_text user "Author: Antmicro"
			(at -1.4224 -4.799 90)
			(layer "B.Fab")
			(hide yes)
			(effects
				(font
					(size 0.7 0.7)
					(thickness 0.15)
				)
				(justify right bottom mirror)
			)
		)
		(fp_text user "License: Apache-2.0"
			(at -1.4224 -3.599 90)
			(layer "B.Fab")
			(hide yes)
			(effects
				(font
					(size 0.7 0.7)
					(thickness 0.15)
				)
				(justify right bottom mirror)
			)
		)
		(fp_text user "${REFERENCE}"
			(at -1.4224 -5.999 90)
			(layer "B.Fab")
			(hide yes)
			(effects
				(font
					(size 0.7 0.7)
					(thickness 0.15)
				)
				(justify right bottom mirror)
			)
		)
		(pad "1" smd roundrect
			(at -0.7 0 270)
			(size 0.8 1)
			(layers "B.Cu" "B.Paste" "B.Mask")
			(roundrect_rratio 0.2)
			(net 1 "GND")
			(pinfunction "C")
			(pintype "passive")
		)
		(pad "2" smd roundrect
			(at 0.7 0 270)
			(size 0.8 1)
			(layers "B.Cu" "B.Paste" "B.Mask")
			(roundrect_rratio 0.2)
			(net 661 "Net-(D54-A)")
			(pinfunction "A")
			(pintype "passive")
		)
	)
	(footprint "antmicro-footprints:R_0402_1005Metric"
		(layer "B.Cu")
		(at 85.5 106.4 -45)
		(descr "Resistor SMD 0402")
		(tags "resistor SMD 0402")
		(property "Reference" "R207"
			(at -0.035355 2.227386 -45)
			(layer "B.SilkS")
			(effects
				(font
					(size 0.7 0.7)
					(thickness 0.15)
				)
				(justify left bottom mirror)
			)
		)
		(property "Value" "R_100k_0402"
			(at 0 -1.399999 135)
			(layer "B.Fab")
			(effects
				(font
					(size 0.7 0.7)
					(thickness 0.15)
				)
				(justify left bottom mirror)
			)
		)
		(property "Footprint" "antmicro-footprints:R_0402_1005Metric"
			(at 0 0 -45)
			(layer "F.Fab")
			(hide yes)
			(effects
				(font
					(size 1.27 1.27)
					(thickness 0.15)
				)
			)
		)
		(property "Datasheet" "https://www.bourns.com/docs/product-datasheets/cr.pdf"
			(at 0 0 -45)
			(layer "F.Fab")
			(hide yes)
			(effects
				(font
					(size 1.27 1.27)
					(thickness 0.15)
				)
			)
		)
		(property "Author" "Antmicro"
			(at -50.193792 91.621468 0)
			(layer "B.Fab")
			(hide yes)
			(effects
				(font
					(size 1 1)
					(thickness 0.15)
				)
				(justify mirror)
			)
		)
		(property "License" "Apache-2.0"
			(at -50.193792 91.621468 0)
			(layer "B.Fab")
			(hide yes)
			(effects
				(font
					(size 1 1)
					(thickness 0.15)
				)
				(justify mirror)
			)
		)
		(property "MPN" "CR0402-FX-1003GLF"
			(at -50.193792 91.621468 0)
			(layer "B.Fab")
			(hide yes)
			(effects
				(font
					(size 1 1)
					(thickness 0.15)
				)
				(justify mirror)
			)
		)
		(property "Manufacturer" "Bourns"
			(at -50.193792 91.621468 0)
			(layer "B.Fab")
			(hide yes)
			(effects
				(font
					(size 1 1)
					(thickness 0.15)
				)
				(justify mirror)
			)
		)
		(property "Tolerance" "1%"
			(at -50.193792 91.621468 0)
			(layer "B.Fab")
			(hide yes)
			(effects
				(font
					(size 1 1)
					(thickness 0.15)
				)
				(justify mirror)
			)
		)
		(property "Val" "100k"
			(at -50.193792 91.621468 0)
			(layer "B.Fab")
			(hide yes)
			(effects
				(font
					(size 1 1)
					(thickness 0.15)
				)
				(justify mirror)
			)
		)
		(sheetname "USB Debug, DP")
		(sheetfile "usb.kicad_sch")
		(attr smd)
		(fp_poly
			(pts
				(xy -0.925 0.47) (xy 0.925 0.47) (xy 0.925 -0.47) (xy -0.925 -0.47)
			)
			(stroke
				(width 0.05)
				(type default)
			)
			(fill none)
			(layer "B.CrtYd")
		)
		(fp_poly
			(pts
				(xy -0.5 0.25) (xy 0.5 0.25) (xy 0.5 -0.25) (xy -0.5 -0.25)
			)
			(stroke
				(width 0.15)
				(type solid)
			)
			(fill none)
			(layer "B.Fab")
		)
		(fp_text user "${REFERENCE}"
			(at -0.95 -3.168 135)
			(layer "B.Fab")
			(hide yes)
			(effects
				(font
					(size 0.7 0.7)
					(thickness 0.15)
				)
				(justify left bottom mirror)
			)
		)
		(fp_text user "Author: Antmicro"
			(at -0.95 -4.169 135)
			(layer "B.Fab")
			(hide yes)
			(effects
				(font
					(size 0.7 0.7)
					(thickness 0.15)
				)
				(justify left bottom mirror)
			)
		)
		(fp_text user "License: Apache-2.0"
			(at -0.949999 -5.169 135)
			(layer "B.Fab")
			(hide yes)
			(effects
				(font
					(size 0.7 0.7)
					(thickness 0.15)
				)
				(justify left bottom mirror)
			)
		)
		(pad "1" smd roundrect
			(at -0.48 0 315)
			(size 0.59 0.64)
			(layers "B.Cu" "B.Paste" "B.Mask")
			(roundrect_rratio 0.25)
			(net 35 "DP1_AUX_N")
			(pintype "passive")
		)
		(pad "2" smd roundrect
			(at 0.48 0 315)
			(size 0.59 0.64)
			(layers "B.Cu" "B.Paste" "B.Mask")
			(roundrect_rratio 0.25)
			(net 87 "+3V3")
			(pintype "passive")
		)
	)
	(footprint "antmicro-footprints:R_0402_1005Metric"
		(layer "B.Cu")
		(at 56.84 80.7)
		(descr "Resistor SMD 0402")
		(tags "resistor SMD 0402")
		(property "Reference" "R236"
			(at 2.535 1.25 180)
			(layer "B.SilkS")
			(effects
				(font
					(size 0.7 0.7)
					(thickness 0.15)
				)
				(justify left bottom mirror)
			)
		)
		(property "Value" "R_200R_0402"
			(at 0 -1.4 180)
			(layer "B.Fab")
			(effects
				(font
					(size 0.7 0.7)
					(thickness 0.15)
				)
				(justify left bottom mirror)
			)
		)
		(property "Footprint" "antmicro-footprints:R_0402_1005Metric"
			(at 0 0 0)
			(layer "F.Fab")
			(hide yes)
			(effects
				(font
					(size 1.27 1.27)
					(thickness 0.15)
				)
			)
		)
		(property "Datasheet" "https://www.bourns.com/docs/product-datasheets/cr.pdf"
			(at 0 0 0)
			(layer "F.Fab")
			(hide yes)
			(effects
				(font
					(size 1.27 1.27)
					(thickness 0.15)
				)
			)
		)
		(property "Author" "Antmicro"
			(at 0 0 0)
			(layer "B.Fab")
			(hide yes)
			(effects
				(font
					(size 1 1)
					(thickness 0.15)
				)
				(justify mirror)
			)
		)
		(property "License" "Apache-2.0"
			(at 0 0 0)
			(layer "B.Fab")
			(hide yes)
			(effects
				(font
					(size 1 1)
					(thickness 0.15)
				)
				(justify mirror)
			)
		)
		(property "MPN" "CR0402-FX-2000GLF"
			(at 0 0 0)
			(layer "B.Fab")
			(hide yes)
			(effects
				(font
					(size 1 1)
					(thickness 0.15)
				)
				(justify mirror)
			)
		)
		(property "Manufacturer" "Bourns"
			(at 0 0 0)
			(layer "B.Fab")
			(hide yes)
			(effects
				(font
					(size 1 1)
					(thickness 0.15)
				)
				(justify mirror)
			)
		)
		(property "Tolerance" "1%"
			(at 0 0 0)
			(layer "B.Fab")
			(hide yes)
			(effects
				(font
					(size 1 1)
					(thickness 0.15)
				)
				(justify mirror)
			)
		)
		(property "Val" "200R"
			(at 0 0 0)
			(layer "B.Fab")
			(hide yes)
			(effects
				(font
					(size 1 1)
					(thickness 0.15)
				)
				(justify mirror)
			)
		)
		(sheetname "Supply")
		(sheetfile "supply.kicad_sch")
		(attr smd)
		(fp_rect
			(start -0.925 0.47)
			(end 0.925 -0.47)
			(stroke
				(width 0.05)
				(type default)
			)
			(fill none)
			(layer "B.CrtYd")
		)
		(fp_rect
			(start -0.5 0.25)
			(end 0.5 -0.25)
			(stroke
				(width 0.15)
				(type solid)
			)
			(fill none)
			(layer "B.Fab")
		)
		(fp_text user "Author: Antmicro"
			(at -0.95 -4.169 180)
			(layer "B.Fab")
			(hide yes)
			(effects
				(font
					(size 0.7 0.7)
					(thickness 0.15)
				)
				(justify left bottom mirror)
			)
		)
		(fp_text user "${REFERENCE}"
			(at -0.95 -3.168 180)
			(layer "B.Fab")
			(hide yes)
			(effects
				(font
					(size 0.7 0.7)
					(thickness 0.15)
				)
				(justify left bottom mirror)
			)
		)
		(fp_text user "License: Apache-2.0"
			(at -0.95 -5.169 180)
			(layer "B.Fab")
			(hide yes)
			(effects
				(font
					(size 0.7 0.7)
					(thickness 0.15)
				)
				(justify left bottom mirror)
			)
		)
		(pad "1" smd roundrect
			(at -0.48 0)
			(size 0.59 0.64)
			(layers "B.Cu" "B.Paste" "B.Mask")
			(roundrect_rratio 0.25)
			(net 342 "Net-(D37-C)")
			(pintype "passive")
		)
		(pad "2" smd roundrect
			(at 0.48 0)
			(size 0.59 0.64)
			(layers "B.Cu" "B.Paste" "B.Mask")
			(roundrect_rratio 0.25)
			(net 474 "~{SHUTDOWN_REQ}")
			(pintype "passive")
		)
	)
)
